# BASEBOARD_FAB2 (Tioga Pass) — schematic netlist excerpt (pin names and nets, part order shuffled) for the footprints in the layout excerpt that follows; sources: Cadence DE-HDL packaged netlist, KiCad conversion of Wiwynn_Tioga_Pass_MB.brd

R8G19  RES  0.0 5% CHIP  pkg 0402  page 189 : A = JTAG_TDI ; B = JTAG_TDI_R
C8B14  CAP_A  22.0UF 4V 20% X6S  pkg 0603V  page 131 : A = P1V05_PCH_STBY ; B = GND
C4G13  CAP  1000PF 50V 10% X7R  pkg 0402LF  page 229 : A = PWRGD_PVTT_GHJ_CPU1_R ; B = GND

(kicad_pcb
	(version 20260206)
	(generator "pcbnew")
	(generator_version "10.0")
	(general
		(thickness 1.6)
		(legacy_teardrops no)
	)
	(paper "A4")
	(title_block
		(title "Wiwynn_Tioga_Pass_MB.brd")
		(comment 1 "Tioga Pass / footprints 1162-1164 of 4770")
	)
	(layers
		(0 "F.Cu" signal "TOP")
		(4 "In1.Cu" signal "L2GND")
		(6 "In2.Cu" signal "L3")
		(8 "In3.Cu" signal "L4GND")
		(10 "In4.Cu" signal "L5")
		(12 "In5.Cu" signal "L6GND")
		(14 "In6.Cu" signal "L7VCC")
		(16 "In7.Cu" signal "L8VCC")
		(18 "In8.Cu" signal "L9GND")
		(20 "In9.Cu" signal "L10")
		(22 "In10.Cu" signal "L11GND")
		(24 "In11.Cu" signal "L12")
		(26 "In12.Cu" signal "L13GND")
		(2 "B.Cu" signal "BOTTOM")
		(9 "F.Adhes" user "F.Adhesive")
		(11 "B.Adhes" user "B.Adhesive")
		(13 "F.Paste" user "Package Geometry/Pastemask Top")
		(15 "B.Paste" user "Package Geometry/Pastemask Bottom")
		(5 "F.SilkS" user "Ref Des/Silkscreen Top")
		(7 "B.SilkS" user "Ref Des/Silkscreen Bottom")
		(1 "F.Mask" user "Board Geometry/Soldermask Top")
		(3 "B.Mask" user "Board Geometry/Soldermask Bottom")
		(17 "Dwgs.User" user "User.Drawings")
		(19 "Cmts.User" user "User.Comments")
		(21 "Eco1.User" user "User.Eco1")
		(23 "Eco2.User" user "User.Eco2")
		(25 "Edge.Cuts" user "Board Geometry/Outline")
		(27 "Margin" user)
		(31 "F.CrtYd" user "Package Geometry/Place Bound Top")
		(29 "B.CrtYd" user "Package Geometry/Place Bound Bottom")
		(35 "F.Fab" user "Ref Des/Assembly Top")
		(33 "B.Fab" user "Ref Des/Assembly Bottom")
	)
	(footprint ""
		(layer "F.Cu")
		(at 173.5836 -4.5466 90)
		(property "Reference" "C4G13"
			(at 0 0 90)
			(layer "F.SilkS")
			(hide yes)
			(effects
				(font
					(size 1.27 1.27)
				)
			)
		)
		(property "Value" ""
			(at 0 0 90)
			(layer "F.Fab")
			(effects
				(font
					(size 1.27 1.27)
				)
			)
		)
		(duplicate_pad_numbers_are_jumpers no)
		(fp_rect
			(start 0.3048 0.9906)
			(end -0.3048 -0.1016)
			(stroke
				(width 0)
				(type default)
			)
			(fill no)
			(layer "F.CrtYd")
		)
		(fp_line
			(start 0.3048 -0.1016)
			(end -0.3048 -0.1016)
			(stroke
				(width 0.1)
				(type default)
			)
			(layer "F.Fab")
		)
		(fp_line
			(start -0.3048 -0.1016)
			(end -0.3048 0.9906)
			(stroke
				(width 0.1)
				(type default)
			)
			(layer "F.Fab")
		)
		(fp_line
			(start 0.3048 0.9906)
			(end 0.3048 -0.1016)
			(stroke
				(width 0.1)
				(type default)
			)
			(layer "F.Fab")
		)
		(fp_line
			(start -0.3048 0.9906)
			(end 0.3048 0.9906)
			(stroke
				(width 0.1)
				(type default)
			)
			(layer "F.Fab")
		)
		(pad "1" smd rect
			(at 0 0 90)
			(size 0.508 0.508)
			(layers "F.Cu" "F.Mask" "F.Paste")
			(net "PWRGD_PVTT_GHJ_CPU1_R")
		)
		(pad "2" smd rect
			(at 0 0.889 90)
			(size 0.508 0.508)
			(layers "F.Cu" "F.Mask" "F.Paste")
			(net "GND")
		)
		(zone
			(layer "F.Cu")
			(hatch none 0.5)
			(connect_pads
				(clearance 0)
			)
			(min_thickness 0.25)
			(keepout
				(tracks allowed)
				(vias not_allowed)
				(pads allowed)
				(copperpour not_allowed)
				(footprints allowed)
			)
			(placement
				(enabled no)
				(sheetname "")
			)
			(fill
				(thermal_gap 0.5)
				(thermal_bridge_width 0.5)
				(island_removal_mode 0)
			)
			(polygon
				(pts
					(xy 174.2186 -4.8006) (xy 173.8376 -4.8006) (xy 173.8376 -4.2926) (xy 174.2186 -4.2926)
				)
			)
		)
		(zone
			(layer "F.Cu")
			(hatch none 0.5)
			(connect_pads
				(clearance 0)
			)
			(min_thickness 0.25)
			(keepout
				(tracks not_allowed)
				(vias allowed)
				(pads allowed)
				(copperpour not_allowed)
				(footprints allowed)
			)
			(placement
				(enabled no)
				(sheetname "")
			)
			(fill
				(thermal_gap 0.5)
				(thermal_bridge_width 0.5)
				(island_removal_mode 0)
			)
			(polygon
				(pts
					(xy 174.2186 -4.8006) (xy 173.8376 -4.8006) (xy 173.8376 -4.2926) (xy 174.2186 -4.2926)
				)
			)
		)
	)
	(footprint ""
		(layer "F.Cu")
		(at 405.1935 -118.237 90)
		(property "Reference" "C8B14"
			(at 0 0 90)
			(layer "F.SilkS")
			(hide yes)
			(effects
				(font
					(size 1.27 1.27)
				)
			)
		)
		(property "Value" ""
			(at 0 0 90)
			(layer "F.Fab")
			(effects
				(font
					(size 1.27 1.27)
				)
			)
		)
		(duplicate_pad_numbers_are_jumpers no)
		(fp_poly
			(pts
				(xy -0.4953 -0.2032) (xy 0.4953 -0.2032) (xy 0.4953 1.6002) (xy -0.4953 1.6002)
			)
			(stroke
				(width 0)
				(type default)
			)
			(fill no)
			(layer "F.CrtYd")
		)
		(fp_line
			(start 0.4953 -0.2032)
			(end 0.4953 1.6002)
			(stroke
				(width 0.1)
				(type default)
			)
			(layer "F.Fab")
		)
		(fp_line
			(start -0.4953 -0.2032)
			(end 0.4953 -0.2032)
			(stroke
				(width 0.1)
				(type default)
			)
			(layer "F.Fab")
		)
		(fp_line
			(start 0.4953 1.6002)
			(end -0.4953 1.6002)
			(stroke
				(width 0.1)
				(type default)
			)
			(layer "F.Fab")
		)
		(fp_line
			(start -0.4953 1.6002)
			(end -0.4953 -0.2032)
			(stroke
				(width 0.1)
				(type default)
			)
			(layer "F.Fab")
		)
		(pad "1" smd rect
			(at 0 0 90)
			(size 0.762 0.889)
			(layers "F.Cu" "F.Mask" "F.Paste")
			(net "P1V05_PCH_STBY")
		)
		(pad "2" smd rect
			(at 0 1.397 90)
			(size 0.762 0.889)
			(layers "F.Cu" "F.Mask" "F.Paste")
			(net "GND")
		)
		(zone
			(layer "F.Cu")
			(hatch none 0.5)
			(connect_pads
				(clearance 0)
			)
			(min_thickness 0.25)
			(keepout
				(tracks not_allowed)
				(vias allowed)
				(pads allowed)
				(copperpour not_allowed)
				(footprints allowed)
			)
			(placement
				(enabled no)
				(sheetname "")
			)
			(fill
				(thermal_gap 0.5)
				(thermal_bridge_width 0.5)
				(island_removal_mode 0)
			)
			(polygon
				(pts
					(xy 405.638 -117.856) (xy 405.638 -118.618) (xy 406.146 -118.618) (xy 406.146 -117.856)
				)
			)
		)
	)
	(footprint ""
		(layer "F.Cu")
		(at 390.271 1.651 -90)
		(property "Reference" "R8G19"
			(at 0 0 270)
			(layer "F.SilkS")
			(hide yes)
			(effects
				(font
					(size 1.27 1.27)
				)
			)
		)
		(property "Value" ""
			(at 0 0 270)
			(layer "F.Fab")
			(effects
				(font
					(size 1.27 1.27)
				)
			)
		)
		(duplicate_pad_numbers_are_jumpers no)
		(fp_poly
			(pts
				(xy -0.2794 -0.1016) (xy 0.2794 -0.1016) (xy 0.2794 0.9906) (xy -0.2794 0.9906)
			)
			(stroke
				(width 0)
				(type default)
			)
			(fill no)
			(layer "F.CrtYd")
		)
		(fp_line
			(start -0.2794 0.9906)
			(end 0.2794 0.9906)
			(stroke
				(width 0.1)
				(type default)
			)
			(layer "F.Fab")
		)
		(fp_line
			(start 0.2794 0.9906)
			(end 0.2794 -0.1016)
			(stroke
				(width 0.1)
				(type default)
			)
			(layer "F.Fab")
		)
		(fp_line
			(start -0.2794 -0.1016)
			(end -0.2794 0.9906)
			(stroke
				(width 0.1)
				(type default)
			)
			(layer "F.Fab")
		)
		(fp_line
			(start 0.2794 -0.1016)
			(end -0.2794 -0.1016)
			(stroke
				(width 0.1)
				(type default)
			)
			(layer "F.Fab")
		)
		(pad "1" smd rect
			(at 0 0 270)
			(size 0.508 0.508)
			(layers "F.Cu" "F.Mask" "F.Paste")
			(net "JTAG_TDI")
		)
		(pad "2" smd rect
			(at 0 0.889 270)
			(size 0.508 0.508)
			(layers "F.Cu" "F.Mask" "F.Paste")
			(net "JTAG_TDI_R")
		)
		(zone
			(layer "F.Cu")
			(hatch none 0.5)
			(connect_pads
				(clearance 0)
			)
			(min_thickness 0.25)
			(keepout
				(tracks not_allowed)
				(vias allowed)
				(pads allowed)
				(copperpour not_allowed)
				(footprints allowed)
			)
			(placement
				(enabled no)
				(sheetname "")
			)
			(fill
				(thermal_gap 0.5)
				(thermal_bridge_width 0.5)
				(island_removal_mode 0)
			)
			(polygon
				(pts
					(xy 389.636 1.397) (xy 389.636 1.905) (xy 390.017 1.905) (xy 390.017 1.397)
				)
			)
		)
		(zone
			(layer "F.Cu")
			(hatch none 0.5)
			(connect_pads
				(clearance 0)
			)
			(min_thickness 0.25)
			(keepout
				(tracks allowed)
				(vias not_allowed)
				(pads allowed)
				(copperpour not_allowed)
				(footprints allowed)
			)
			(placement
				(enabled no)
				(sheetname "")
			)
			(fill
				(thermal_gap 0.5)
				(thermal_bridge_width 0.5)
				(island_removal_mode 0)
			)
			(polygon
				(pts
					(xy 390.017 1.397) (xy 390.017 1.905) (xy 389.636 1.905) (xy 389.636 1.397)
				)
			)
		)
	)
)
